# BASEBOARD_FAB2 (Tioga Pass) — schematic netlist excerpt (pin names and nets, part order shuffled) for the footprints in the layout excerpt that follows; sources: Cadence DE-HDL packaged netlist, KiCad conversion of Wiwynn_Tioga_Pass_MB.brd

CF5  SC22P50V2JN-4GP  5%  pkg SMD-BCG  page 201 : \1\ = VR_PVCCIN_CPU0_AIREF5 ; \2\ = ISENSE_PVCCIN_CPU0_PH5_IMON
C1E20  CAP_A  0.1UF 16V 10% X7R  pkg 0402V  page 161 : A = P12V_FAN ; B = GND
RF16  RES  1.0K 0.1% CHIP  pkg 0402  page 215 : A = VR_PVDDQ_ABC_AIREF2 ; B = ISENSE_PVDDQ_ABC_PH2_IMON

(kicad_pcb
	(version 20260206)
	(generator "pcbnew")
	(generator_version "10.0")
	(general
		(thickness 1.6)
		(legacy_teardrops no)
	)
	(paper "A4")
	(title_block
		(title "Wiwynn_Tioga_Pass_MB.brd")
		(comment 1 "Tioga Pass / footprints 1704-1706 of 4770")
	)
	(layers
		(0 "F.Cu" signal "TOP")
		(4 "In1.Cu" signal "L2GND")
		(6 "In2.Cu" signal "L3")
		(8 "In3.Cu" signal "L4GND")
		(10 "In4.Cu" signal "L5")
		(12 "In5.Cu" signal "L6GND")
		(14 "In6.Cu" signal "L7VCC")
		(16 "In7.Cu" signal "L8VCC")
		(18 "In8.Cu" signal "L9GND")
		(20 "In9.Cu" signal "L10")
		(22 "In10.Cu" signal "L11GND")
		(24 "In11.Cu" signal "L12")
		(26 "In12.Cu" signal "L13GND")
		(2 "B.Cu" signal "BOTTOM")
		(9 "F.Adhes" user "F.Adhesive")
		(11 "B.Adhes" user "B.Adhesive")
		(13 "F.Paste" user "Package Geometry/Pastemask Top")
		(15 "B.Paste" user "Package Geometry/Pastemask Bottom")
		(5 "F.SilkS" user "Ref Des/Silkscreen Top")
		(7 "B.SilkS" user "Ref Des/Silkscreen Bottom")
		(1 "F.Mask" user "Board Geometry/Soldermask Top")
		(3 "B.Mask" user "Board Geometry/Soldermask Bottom")
		(17 "Dwgs.User" user "User.Drawings")
		(19 "Cmts.User" user "User.Comments")
		(21 "Eco1.User" user "User.Eco1")
		(23 "Eco2.User" user "User.Eco2")
		(25 "Edge.Cuts" user "Board Geometry/Outline")
		(27 "Margin" user)
		(31 "F.CrtYd" user "Package Geometry/Place Bound Top")
		(29 "B.CrtYd" user "Package Geometry/Place Bound Bottom")
		(35 "F.Fab" user "Ref Des/Assembly Top")
		(33 "B.Fab" user "Ref Des/Assembly Bottom")
	)
	(footprint ""
		(layer "F.Cu")
		(at 344.42654 -10.686796 180)
		(property "Reference" "RF16"
			(at -0.8382 -0.67818 180)
			(unlocked yes)
			(layer "F.SilkS")
			(effects
				(font
					(size 0.4064 0.254)
					(thickness 0.1524)
				)
				(justify left)
			)
		)
		(property "Value" ""
			(at 0 0 180)
			(layer "F.Fab")
			(effects
				(font
					(size 1.27 1.27)
				)
			)
		)
		(duplicate_pad_numbers_are_jumpers no)
		(fp_poly
			(pts
				(xy -0.2794 -0.1016) (xy 0.2794 -0.1016) (xy 0.2794 0.9906) (xy -0.2794 0.9906)
			)
			(stroke
				(width 0)
				(type default)
			)
			(fill no)
			(layer "F.CrtYd")
		)
		(fp_line
			(start 0.2794 0.9906)
			(end 0.2794 -0.1016)
			(stroke
				(width 0.1)
				(type default)
			)
			(layer "F.Fab")
		)
		(fp_line
			(start 0.2794 -0.1016)
			(end -0.2794 -0.1016)
			(stroke
				(width 0.1)
				(type default)
			)
			(layer "F.Fab")
		)
		(fp_line
			(start -0.2794 0.9906)
			(end 0.2794 0.9906)
			(stroke
				(width 0.1)
				(type default)
			)
			(layer "F.Fab")
		)
		(fp_line
			(start -0.2794 -0.1016)
			(end -0.2794 0.9906)
			(stroke
				(width 0.1)
				(type default)
			)
			(layer "F.Fab")
		)
		(pad "1" smd rect
			(at 0 0 180)
			(size 0.508 0.508)
			(layers "F.Cu" "F.Mask" "F.Paste")
			(net "VR_PVDDQ_ABC_AIREF2")
		)
		(pad "2" smd rect
			(at 0 0.889 180)
			(size 0.508 0.508)
			(layers "F.Cu" "F.Mask" "F.Paste")
			(net "ISENSE_PVDDQ_ABC_PH2_IMON")
		)
		(zone
			(layer "F.Cu")
			(hatch none 0.5)
			(connect_pads
				(clearance 0)
			)
			(min_thickness 0.25)
			(keepout
				(tracks not_allowed)
				(vias allowed)
				(pads allowed)
				(copperpour not_allowed)
				(footprints allowed)
			)
			(placement
				(enabled no)
				(sheetname "")
			)
			(fill
				(thermal_gap 0.5)
				(thermal_bridge_width 0.5)
				(island_removal_mode 0)
			)
			(polygon
				(pts
					(xy 344.68054 -11.321796) (xy 344.17254 -11.321796) (xy 344.17254 -10.940796) (xy 344.68054 -10.940796)
				)
			)
		)
		(zone
			(layer "F.Cu")
			(hatch none 0.5)
			(connect_pads
				(clearance 0)
			)
			(min_thickness 0.25)
			(keepout
				(tracks allowed)
				(vias not_allowed)
				(pads allowed)
				(copperpour not_allowed)
				(footprints allowed)
			)
			(placement
				(enabled no)
				(sheetname "")
			)
			(fill
				(thermal_gap 0.5)
				(thermal_bridge_width 0.5)
				(island_removal_mode 0)
			)
			(polygon
				(pts
					(xy 344.68054 -10.940796) (xy 344.17254 -10.940796) (xy 344.17254 -11.321796) (xy 344.68054 -11.321796)
				)
			)
		)
	)
	(footprint ""
		(layer "F.Cu")
		(at 189.3316 -71.1454 180)
		(property "Reference" "CF5"
			(at 0 0 180)
			(layer "F.SilkS")
			(hide yes)
			(effects
				(font
					(size 1.27 1.27)
				)
			)
		)
		(property "Value" "*"
			(at 1.1811 -2.8194 180)
			(unlocked yes)
			(layer "F.Fab")
			(hide yes)
			(effects
				(font
					(size 1.27 1.016)
					(thickness 0.1524)
				)
			)
		)
		(property "Device Type" "SC22P50V2JN-4GP_SMD-BCG-SC22P5A"
			(at 1.1811 -4.3434 180)
			(unlocked yes)
			(layer "F.Fab")
			(hide yes)
			(effects
				(font
					(size 1.27 1.016)
					(thickness 0.1524)
				)
			)
		)
		(duplicate_pad_numbers_are_jumpers no)
		(fp_rect
			(start -0.4318 0.9525)
			(end 0.4318 -0.9525)
			(stroke
				(width 0)
				(type default)
			)
			(fill no)
			(layer "F.CrtYd")
		)
		(fp_rect
			(start -0.4318 0.9525)
			(end 0.4318 -0.9525)
			(stroke
				(width 0)
				(type default)
			)
			(fill no)
			(layer "F.Fab")
		)
		(pad "1" smd custom
			(at 0 -0.4445 180)
			(size 0.1524 0.1524)
			(layers "F.Cu" "F.Mask" "F.Paste")
			(net "VR_PVCCIN_CPU0_AIREF5")
			(options
				(clearance outline)
				(anchor circle)
			)
			(primitives
				(gr_poly
					(pts
						(arc
							(start 0.3048 -0.2032)
							(mid 0.275042 -0.275042)
							(end 0.2032 -0.3048)
						)
						(arc
							(start -0.2032 -0.3048)
							(mid -0.275042 -0.275042)
							(end -0.3048 -0.2032)
						)
						(arc
							(start -0.3048 0.2032)
							(mid -0.275042 0.275042)
							(end -0.2032 0.3048)
						)
						(arc
							(start 0.2032 0.3048)
							(mid 0.275042 0.275042)
							(end 0.3048 0.2032)
						)
					)
					(width 0)
					(fill yes)
				)
			)
		)
		(pad "2" smd custom
			(at 0 0.4445 180)
			(size 0.1524 0.1524)
			(layers "F.Cu" "F.Mask" "F.Paste")
			(net "ISENSE_PVCCIN_CPU0_PH5_IMON")
			(options
				(clearance outline)
				(anchor circle)
			)
			(primitives
				(gr_poly
					(pts
						(arc
							(start 0.3048 -0.2032)
							(mid 0.275042 -0.275042)
							(end 0.2032 -0.3048)
						)
						(arc
							(start -0.2032 -0.3048)
							(mid -0.275042 -0.275042)
							(end -0.3048 -0.2032)
						)
						(arc
							(start -0.3048 0.2032)
							(mid -0.275042 0.275042)
							(end -0.2032 0.3048)
						)
						(arc
							(start 0.2032 0.3048)
							(mid 0.275042 0.275042)
							(end 0.3048 0.2032)
						)
					)
					(width 0)
					(fill yes)
				)
			)
		)
	)
	(footprint ""
		(layer "F.Cu")
		(at 29.83865 -41.8592 180)
		(property "Reference" "C1E20"
			(at 0 0 180)
			(layer "F.SilkS")
			(hide yes)
			(effects
				(font
					(size 1.27 1.27)
				)
			)
		)
		(property "Value" ""
			(at 0 0 180)
			(layer "F.Fab")
			(effects
				(font
					(size 1.27 1.27)
				)
			)
		)
		(duplicate_pad_numbers_are_jumpers no)
		(fp_rect
			(start 0.3048 -0.1016)
			(end -0.3048 0.9906)
			(stroke
				(width 0)
				(type default)
			)
			(fill no)
			(layer "F.CrtYd")
		)
		(fp_line
			(start 0.3048 0.9906)
			(end 0.3048 -0.1016)
			(stroke
				(width 0.1)
				(type default)
			)
			(layer "F.Fab")
		)
		(fp_line
			(start 0.3048 -0.1016)
			(end -0.3048 -0.1016)
			(stroke
				(width 0.1)
				(type default)
			)
			(layer "F.Fab")
		)
		(fp_line
			(start -0.3048 0.9906)
			(end 0.3048 0.9906)
			(stroke
				(width 0.1)
				(type default)
			)
			(layer "F.Fab")
		)
		(fp_line
			(start -0.3048 -0.1016)
			(end -0.3048 0.9906)
			(stroke
				(width 0.1)
				(type default)
			)
			(layer "F.Fab")
		)
		(pad "1" smd rect
			(at 0 0 180)
			(size 0.508 0.508)
			(layers "F.Cu" "F.Mask" "F.Paste")
			(net "P12V_FAN")
		)
		(pad "2" smd rect
			(at 0 0.889 180)
			(size 0.508 0.508)
			(layers "F.Cu" "F.Mask" "F.Paste")
			(net "GND")
		)
		(zone
			(layer "F.Cu")
			(hatch none 0.5)
			(connect_pads
				(clearance 0)
			)
			(min_thickness 0.25)
			(keepout
				(tracks allowed)
				(vias not_allowed)
				(pads allowed)
				(copperpour not_allowed)
				(footprints allowed)
			)
			(placement
				(enabled no)
				(sheetname "")
			)
			(fill
				(thermal_gap 0.5)
				(thermal_bridge_width 0.5)
				(island_removal_mode 0)
			)
			(polygon
				(pts
					(xy 29.58465 -42.1132) (xy 30.09265 -42.1132) (xy 30.09265 -42.4942) (xy 29.58465 -42.4942)
				)
			)
		)
		(zone
			(layer "F.Cu")
			(hatch none 0.5)
			(connect_pads
				(clearance 0)
			)
			(min_thickness 0.25)
			(keepout
				(tracks not_allowed)
				(vias allowed)
				(pads allowed)
				(copperpour not_allowed)
				(footprints allowed)
			)
			(placement
				(enabled no)
				(sheetname "")
			)
			(fill
				(thermal_gap 0.5)
				(thermal_bridge_width 0.5)
				(island_removal_mode 0)
			)
			(polygon
				(pts
					(xy 29.58465 -42.1132) (xy 30.09265 -42.1132) (xy 30.09265 -42.4942) (xy 29.58465 -42.4942)
				)
			)
		)
	)
)
